# S9S_MB_2U (Grand Teton) — schematic netlist excerpt (pin names and nets, part order shuffled) for the footprints in the layout excerpt that follows; sources: Cadence DE-HDL packaged netlist, KiCad conversion of 03242023_DA0F0TMBIJ0_F0T_Motherboard_J_brd_V01_OCP.brd

R4723  Q_RES  33.2 1% CHIP  pkg 0402LF  page 215 : A = FM_PCH_BMC_RST_R_N ; B = FM_PCH_BMC_RST_N
R1607  Q_RES  0 5% EMPTY  pkg 0402LF  page 260 : A = FM_PS_EN_PLD_R ; B = VR_P5V_EN

(kicad_pcb
	(version 20260206)
	(generator "pcbnew")
	(generator_version "10.0")
	(general
		(thickness 1.6)
		(legacy_teardrops no)
	)
	(paper "A4")
	(title_block
		(title "03242023_DA0F0TMBIJ0_F0T_Motherboard_J_brd_V01_OCP.brd")
		(comment 1 "Grand Teton / footprints 3014-3015 of 6105")
	)
	(layers
		(0 "F.Cu" signal "TOP")
		(4 "In1.Cu" signal "GND")
		(6 "In2.Cu" signal "IN1")
		(8 "In3.Cu" signal "GND1")
		(10 "In4.Cu" signal "IN2")
		(12 "In5.Cu" signal "GND2")
		(14 "In6.Cu" signal "IN3")
		(16 "In7.Cu" signal "GND3")
		(18 "In8.Cu" signal "VCC")
		(20 "In9.Cu" signal "VCC1")
		(22 "In10.Cu" signal "GND4")
		(24 "In11.Cu" signal "IN4")
		(26 "In12.Cu" signal "GND5")
		(28 "In13.Cu" signal "IN5")
		(30 "In14.Cu" signal "GND6")
		(32 "In15.Cu" signal "IN6")
		(34 "In16.Cu" signal "GND7")
		(2 "B.Cu" signal "BOTTOM")
		(9 "F.Adhes" user "F.Adhesive")
		(11 "B.Adhes" user "B.Adhesive")
		(13 "F.Paste" user "Package Geometry/Pastemask Top")
		(15 "B.Paste" user "Package Geometry/Pastemask Bottom")
		(5 "F.SilkS" user "Ref Des/Silkscreen Top")
		(7 "B.SilkS" user "Ref Des/Silkscreen Bottom")
		(1 "F.Mask" user "Board Geometry/Soldermask Top")
		(3 "B.Mask" user "Board Geometry/Soldermask Bottom")
		(17 "Dwgs.User" user "User.Drawings")
		(19 "Cmts.User" user "User.Comments")
		(21 "Eco1.User" user "User.Eco1")
		(23 "Eco2.User" user "User.Eco2")
		(25 "Edge.Cuts" user "Board Geometry/Outline")
		(27 "Margin" user)
		(31 "F.CrtYd" user "Package Geometry/Place Bound Top")
		(29 "B.CrtYd" user "Package Geometry/Place Bound Bottom")
		(35 "F.Fab" user "Ref Des/Assembly Top")
		(33 "B.Fab" user "Ref Des/Assembly Bottom")
	)
	(footprint ""
		(layer "F.Cu")
		(at 204.99578 -113.0554 180)
		(property "Reference" "R4723"
			(at 0 0 180)
			(layer "F.SilkS")
			(hide yes)
			(effects
				(font
					(size 1.27 1.27)
				)
			)
		)
		(property "Value" ""
			(at 0 0 180)
			(layer "F.Fab")
			(effects
				(font
					(size 1.27 1.27)
				)
			)
		)
		(duplicate_pad_numbers_are_jumpers no)
		(fp_line
			(start 0.7874 0.4064)
			(end -0.7874 0.4064)
			(stroke
				(width 0.1524)
				(type default)
			)
			(layer "F.SilkS")
		)
		(fp_line
			(start 0.7874 -0.4064)
			(end 0.7874 0.4064)
			(stroke
				(width 0.1524)
				(type default)
			)
			(layer "F.SilkS")
		)
		(fp_line
			(start -0.7874 0.4064)
			(end -0.7874 -0.4064)
			(stroke
				(width 0.1524)
				(type default)
			)
			(layer "F.SilkS")
		)
		(fp_line
			(start -0.7874 -0.4064)
			(end 0.7874 -0.4064)
			(stroke
				(width 0.1524)
				(type default)
			)
			(layer "F.SilkS")
		)
		(fp_line
			(start 0.67945 0.3048)
			(end 0.120396 0.3048)
			(stroke
				(width 0.1)
				(type default)
			)
			(layer "F.Fab")
		)
		(fp_line
			(start 0.67945 -0.3048)
			(end 0.67945 0.3048)
			(stroke
				(width 0.1)
				(type default)
			)
			(layer "F.Fab")
		)
		(fp_line
			(start 0.12065 -0.2794)
			(end 0.12065 -0.3048)
			(stroke
				(width 0.1)
				(type default)
			)
			(layer "F.Fab")
		)
		(fp_line
			(start 0.12065 -0.3048)
			(end 0.67945 -0.3048)
			(stroke
				(width 0.1)
				(type default)
			)
			(layer "F.Fab")
		)
		(fp_line
			(start 0.120396 0.3048)
			(end 0.120396 0.2794)
			(stroke
				(width 0.1)
				(type default)
			)
			(layer "F.Fab")
		)
		(fp_line
			(start 0.120396 0.2794)
			(end -0.12065 0.2794)
			(stroke
				(width 0.1)
				(type default)
			)
			(layer "F.Fab")
		)
		(fp_line
			(start -0.12065 0.3048)
			(end -0.67945 0.3048)
			(stroke
				(width 0.1)
				(type default)
			)
			(layer "F.Fab")
		)
		(fp_line
			(start -0.12065 0.2794)
			(end -0.12065 0.3048)
			(stroke
				(width 0.1)
				(type default)
			)
			(layer "F.Fab")
		)
		(fp_line
			(start -0.12065 -0.2794)
			(end 0.12065 -0.2794)
			(stroke
				(width 0.1)
				(type default)
			)
			(layer "F.Fab")
		)
		(fp_line
			(start -0.12065 -0.305054)
			(end -0.12065 -0.2794)
			(stroke
				(width 0.1)
				(type default)
			)
			(layer "F.Fab")
		)
		(fp_line
			(start -0.67945 0.3048)
			(end -0.67945 -0.305054)
			(stroke
				(width 0.1)
				(type default)
			)
			(layer "F.Fab")
		)
		(fp_line
			(start -0.67945 -0.305054)
			(end -0.12065 -0.305054)
			(stroke
				(width 0.1)
				(type default)
			)
			(layer "F.Fab")
		)
		(pad "1" smd circle
			(at -0.40005 0 180)
			(size 0 0)
			(layers "F.Cu" "F.Mask" "F.Paste")
			(net "FM_PCH_BMC_RST_R_N")
		)
		(pad "2" smd circle
			(at 0.40005 0 180)
			(size 0 0)
			(layers "F.Cu" "F.Mask" "F.Paste")
			(net "FM_PCH_BMC_RST_N")
		)
	)
	(footprint ""
		(layer "F.Cu")
		(at 166.34333 -131.976876 -90)
		(property "Reference" "R1607"
			(at 0 0 270)
			(layer "F.SilkS")
			(hide yes)
			(effects
				(font
					(size 1.27 1.27)
				)
			)
		)
		(property "Value" ""
			(at 0 0 270)
			(layer "F.Fab")
			(effects
				(font
					(size 1.27 1.27)
				)
			)
		)
		(duplicate_pad_numbers_are_jumpers no)
		(fp_line
			(start -0.7874 0.4064)
			(end -0.7874 -0.4064)
			(stroke
				(width 0.1524)
				(type default)
			)
			(layer "F.SilkS")
		)
		(fp_line
			(start 0.7874 0.4064)
			(end -0.7874 0.4064)
			(stroke
				(width 0.1524)
				(type default)
			)
			(layer "F.SilkS")
		)
		(fp_line
			(start -0.7874 -0.4064)
			(end 0.7874 -0.4064)
			(stroke
				(width 0.1524)
				(type default)
			)
			(layer "F.SilkS")
		)
		(fp_line
			(start 0.7874 -0.4064)
			(end 0.7874 0.4064)
			(stroke
				(width 0.1524)
				(type default)
			)
			(layer "F.SilkS")
		)
		(fp_line
			(start -0.67945 0.3048)
			(end -0.67945 -0.305054)
			(stroke
				(width 0.1)
				(type default)
			)
			(layer "F.Fab")
		)
		(fp_line
			(start -0.12065 0.3048)
			(end -0.67945 0.3048)
			(stroke
				(width 0.1)
				(type default)
			)
			(layer "F.Fab")
		)
		(fp_line
			(start 0.120396 0.3048)
			(end 0.120396 0.2794)
			(stroke
				(width 0.1)
				(type default)
			)
			(layer "F.Fab")
		)
		(fp_line
			(start 0.67945 0.3048)
			(end 0.120396 0.3048)
			(stroke
				(width 0.1)
				(type default)
			)
			(layer "F.Fab")
		)
		(fp_line
			(start -0.12065 0.2794)
			(end -0.12065 0.3048)
			(stroke
				(width 0.1)
				(type default)
			)
			(layer "F.Fab")
		)
		(fp_line
			(start 0.120396 0.2794)
			(end -0.12065 0.2794)
			(stroke
				(width 0.1)
				(type default)
			)
			(layer "F.Fab")
		)
		(fp_line
			(start -0.12065 -0.2794)
			(end 0.12065 -0.2794)
			(stroke
				(width 0.1)
				(type default)
			)
			(layer "F.Fab")
		)
		(fp_line
			(start 0.12065 -0.2794)
			(end 0.12065 -0.3048)
			(stroke
				(width 0.1)
				(type default)
			)
			(layer "F.Fab")
		)
		(fp_line
			(start 0.12065 -0.3048)
			(end 0.67945 -0.3048)
			(stroke
				(width 0.1)
				(type default)
			)
			(layer "F.Fab")
		)
		(fp_line
			(start 0.67945 -0.3048)
			(end 0.67945 0.3048)
			(stroke
				(width 0.1)
				(type default)
			)
			(layer "F.Fab")
		)
		(fp_line
			(start -0.67945 -0.305054)
			(end -0.12065 -0.305054)
			(stroke
				(width 0.1)
				(type default)
			)
			(layer "F.Fab")
		)
		(fp_line
			(start -0.12065 -0.305054)
			(end -0.12065 -0.2794)
			(stroke
				(width 0.1)
				(type default)
			)
			(layer "F.Fab")
		)
		(pad "1" smd circle
			(at -0.40005 0 270)
			(size 0 0)
			(layers "F.Cu" "F.Mask" "F.Paste")
			(net "FM_PS_EN_PLD_R")
		)
		(pad "2" smd circle
			(at 0.40005 0 270)
			(size 0 0)
			(layers "F.Cu" "F.Mask" "F.Paste")
			(net "VR_P5V_EN")
		)
	)
)
